FILE_TYPE = MACRO_DRAWING;
SET COLOR_WIRE YELLOW;
SET COLOR_PROP ORANGE;
SET COLOR_DOT WHITE;
SET COLOR_ARC YELLOW;
SET COLOR_BODY GREEN;
SET COLOR_NOTE PURPLE;
SET PROP_DISPLAY VALUE;
SET PAGE_NUMBER P8;
FORCEADD QUANTA_TITLE_BLOCK_C..1
(-100 100);
FORCEPROP 1 LAST CUSTOM_TXT_CDS <NAME_2>
J 0
(-3275 150);
FORCEPROP 1 LAST CUSTOM_TXT_CDS <NAME_1>
J 0
(-3275 275);
FORCEPROP 1 LAST CUSTOM_TXT_CDS <Q_NUMBER>
J 0
(-1503 203);
DISPLAY 1.212766 (-1503 203);
FORCEPROP 1 LAST CUSTOM_TXT_CDS <Q_PROJ>
J 0
(-2482 202);
DISPLAY 1.212766 (-2482 202);
FORCEPROP 1 LAST CUSTOM_TXT_CDS <Q_REV>
J 0
(-284 203);
DISPLAY 1.212766 (-284 203);
FORCEPROP 1 LAST CUSTOM_TXT_CDS <CON_LAST_MODIFIED>
J 0
(-1985 115);
DISPLAY 0.978723 (-1985 115);
FORCEPROP 1 LAST CUSTOM_TXT_CDS <CON_PAGE_NUM> OF <CON_TOTAL_PAGES>
J 0
(-546 118);
DISPLAY 0.978723 (-546 118);
FORCEPROP 1 LAST Q_TITLE BLOCK DIAGRAM - I2C/I3C
J 0
(-9375 175);
DISPLAY 2.446809 (-9375 175);
PAINT GREEN (-9375 175);
FORCEPROP 2 LAST PAGE_BORDER TRUE
J 0
(-7990 5350);
DISPLAY 0.638298 (-7990 5350);
PAINT PINK (-7990 5350);
DISPLAY INVISIBLE (-7990 5350);
FORCEPROP 2 LAST CDS_LIB pure_quanta
J 0
(-100 100);
DISPLAY INVISIBLE (-100 100);
FORCEPROP 1 LAST CDS_LMAN_SYM_OUTLINE -9475,6775,100,-125
J 0
(-100 100);
DISPLAY 0.468085 (-100 100);
PAINT GREEN (-100 100);
DISPLAY INVISIBLE (-100 100);
FORCEPROP 2 LAST CDS_XR_PAGE_TITLE CR-8 : @T6G_MB_LIB.T6G(SCH_1):PAGE8
J 0
(-7990 5350);
DISPLAY 0.638298 (-7990 5350);
PAINT PINK (-7990 5350);
DISPLAY INVISIBLE (-7990 5350);
FORCEPROP 2 LAST CUSTOM_TXT_CDS <XR_PAGE_TITLE>
J 0
(-7990 5350);
DISPLAY 0.638298 (-7990 5350);
PAINT PINK (-7990 5350);
DISPLAY INVISIBLE (-7990 5350);
FORCEPROP 1 LAST COMMENT_BODY TRUE
J 0
(-88 87);
DISPLAY 0.978723 (-88 87);
PAINT GREEN (-88 87);
DISPLAY INVISIBLE (-88 87);
FORCEPROP 1 LAST Q_DEPT BU9
J 1
(-3863 149);
DISPLAY 1.957447 (-3863 149);
PAINT GREEN (-3863 149);
DISPLAY INVISIBLE (-3863 149);
FORCEPROP 0 LAST CDS_CON_LAST_MODIFIED Thu Aug 24 10:13:30 2023
J 0
(-1985 115);
DISPLAY INVISIBLE (-1985 115);
FORCENOTE
$CDS_IMAGE|Grand_Teton_Inference_8 Retimer_Block_Diagram_20230203_REV3-SMBus.jpg|8918|5242
(-4675 3325) 0;
DISPLAY LEFT (-4675 3325);
QUIT
